# S9S_MB_2U (Grand Teton) — schematic netlist excerpt (pin names and nets, part order shuffled) for the footprints in the layout excerpt that follows; sources: Cadence DE-HDL packaged netlist, KiCad conversion of 03242023_DA0F0TMBIJ0_F0T_Motherboard_J_brd_V01_OCP.brd

PC312_P0_1  Q_CAP  22UF 4V 20% X6S  pkg C0805  page 267 : A = PVCCIN_CPU0 ; B = GND
C514  Q_CAP  47UF 4V 20% X6S  pkg C0805  page 76 : A = PVCCFA_EHV_FIVRA_CPU0 ; B = GND
R255  Q_RES  240 1% EMPTY  pkg 0402LF  page 120 : A = PVNN_TERM_CPU1 ; B = FM_S3M_CPU1_LVC1_GPIO_0

(kicad_pcb
	(version 20260206)
	(generator "pcbnew")
	(generator_version "10.0")
	(general
		(thickness 1.6)
		(legacy_teardrops no)
	)
	(paper "A4")
	(title_block
		(title "03242023_DA0F0TMBIJ0_F0T_Motherboard_J_brd_V01_OCP.brd")
		(comment 1 "Grand Teton / footprints 4873-4875 of 6105")
	)
	(layers
		(0 "F.Cu" signal "TOP")
		(4 "In1.Cu" signal "GND")
		(6 "In2.Cu" signal "IN1")
		(8 "In3.Cu" signal "GND1")
		(10 "In4.Cu" signal "IN2")
		(12 "In5.Cu" signal "GND2")
		(14 "In6.Cu" signal "IN3")
		(16 "In7.Cu" signal "GND3")
		(18 "In8.Cu" signal "VCC")
		(20 "In9.Cu" signal "VCC1")
		(22 "In10.Cu" signal "GND4")
		(24 "In11.Cu" signal "IN4")
		(26 "In12.Cu" signal "GND5")
		(28 "In13.Cu" signal "IN5")
		(30 "In14.Cu" signal "GND6")
		(32 "In15.Cu" signal "IN6")
		(34 "In16.Cu" signal "GND7")
		(2 "B.Cu" signal "BOTTOM")
		(9 "F.Adhes" user "F.Adhesive")
		(11 "B.Adhes" user "B.Adhesive")
		(13 "F.Paste" user "Package Geometry/Pastemask Top")
		(15 "B.Paste" user "Package Geometry/Pastemask Bottom")
		(5 "F.SilkS" user "Ref Des/Silkscreen Top")
		(7 "B.SilkS" user "Ref Des/Silkscreen Bottom")
		(1 "F.Mask" user "Board Geometry/Soldermask Top")
		(3 "B.Mask" user "Board Geometry/Soldermask Bottom")
		(17 "Dwgs.User" user "User.Drawings")
		(19 "Cmts.User" user "User.Comments")
		(21 "Eco1.User" user "User.Eco1")
		(23 "Eco2.User" user "User.Eco2")
		(25 "Edge.Cuts" user "Board Geometry/Outline")
		(27 "Margin" user)
		(31 "F.CrtYd" user "Package Geometry/Place Bound Top")
		(29 "B.CrtYd" user "Package Geometry/Place Bound Bottom")
		(35 "F.Fab" user "Ref Des/Assembly Top")
		(33 "B.Fab" user "Ref Des/Assembly Bottom")
	)
	(footprint ""
		(layer "B.Cu")
		(at 48.666908 -193.25971 -90)
		(property "Reference" "R255"
			(at 0 0 90)
			(layer "B.SilkS")
			(hide yes)
			(effects
				(font
					(size 1.27 1.27)
				)
				(justify mirror)
			)
		)
		(property "Value" ""
			(at 0 0 90)
			(layer "B.Fab")
			(effects
				(font
					(size 1.27 1.27)
				)
				(justify mirror)
			)
		)
		(duplicate_pad_numbers_are_jumpers no)
		(fp_line
			(start -0.7874 0.4064)
			(end 0.7874 0.4064)
			(stroke
				(width 0.1524)
				(type default)
			)
			(layer "B.SilkS")
		)
		(fp_line
			(start 0.7874 0.4064)
			(end 0.7874 -0.4064)
			(stroke
				(width 0.1524)
				(type default)
			)
			(layer "B.SilkS")
		)
		(fp_line
			(start -0.7874 -0.4064)
			(end -0.7874 0.4064)
			(stroke
				(width 0.1524)
				(type default)
			)
			(layer "B.SilkS")
		)
		(fp_line
			(start 0.7874 -0.4064)
			(end -0.7874 -0.4064)
			(stroke
				(width 0.1524)
				(type default)
			)
			(layer "B.SilkS")
		)
		(fp_line
			(start -0.67945 0.3048)
			(end -0.120396 0.3048)
			(stroke
				(width 0.1)
				(type default)
			)
			(layer "B.Fab")
		)
		(fp_line
			(start -0.120396 0.3048)
			(end -0.120396 0.2794)
			(stroke
				(width 0.1)
				(type default)
			)
			(layer "B.Fab")
		)
		(fp_line
			(start 0.12065 0.3048)
			(end 0.67945 0.3048)
			(stroke
				(width 0.1)
				(type default)
			)
			(layer "B.Fab")
		)
		(fp_line
			(start 0.67945 0.3048)
			(end 0.67945 -0.305054)
			(stroke
				(width 0.1)
				(type default)
			)
			(layer "B.Fab")
		)
		(fp_line
			(start -0.120396 0.2794)
			(end 0.12065 0.2794)
			(stroke
				(width 0.1)
				(type default)
			)
			(layer "B.Fab")
		)
		(fp_line
			(start 0.12065 0.2794)
			(end 0.12065 0.3048)
			(stroke
				(width 0.1)
				(type default)
			)
			(layer "B.Fab")
		)
		(fp_line
			(start -0.12065 -0.2794)
			(end -0.12065 -0.3048)
			(stroke
				(width 0.1)
				(type default)
			)
			(layer "B.Fab")
		)
		(fp_line
			(start 0.12065 -0.2794)
			(end -0.12065 -0.2794)
			(stroke
				(width 0.1)
				(type default)
			)
			(layer "B.Fab")
		)
		(fp_line
			(start -0.67945 -0.3048)
			(end -0.67945 0.3048)
			(stroke
				(width 0.1)
				(type default)
			)
			(layer "B.Fab")
		)
		(fp_line
			(start -0.12065 -0.3048)
			(end -0.67945 -0.3048)
			(stroke
				(width 0.1)
				(type default)
			)
			(layer "B.Fab")
		)
		(fp_line
			(start 0.12065 -0.305054)
			(end 0.12065 -0.2794)
			(stroke
				(width 0.1)
				(type default)
			)
			(layer "B.Fab")
		)
		(fp_line
			(start 0.67945 -0.305054)
			(end 0.12065 -0.305054)
			(stroke
				(width 0.1)
				(type default)
			)
			(layer "B.Fab")
		)
		(pad "1" smd circle
			(at 0.40005 0 90)
			(size 0 0)
			(layers "B.Cu" "B.Mask" "B.Paste")
			(net "PVNN_TERM_CPU1")
		)
		(pad "2" smd circle
			(at -0.40005 0 90)
			(size 0 0)
			(layers "B.Cu" "B.Mask" "B.Paste")
			(net "FM_S3M_CPU1_LVC1_GPIO_0")
		)
	)
	(footprint ""
		(layer "B.Cu")
		(at 410.816044 -258.207764 -90)
		(property "Reference" "C514"
			(at 0 0 90)
			(layer "B.SilkS")
			(hide yes)
			(effects
				(font
					(size 1.27 1.27)
				)
				(justify mirror)
			)
		)
		(property "Value" ""
			(at 0 0 90)
			(layer "B.Fab")
			(effects
				(font
					(size 1.27 1.27)
				)
				(justify mirror)
			)
		)
		(duplicate_pad_numbers_are_jumpers no)
		(fp_line
			(start -1.524 0.762)
			(end 1.524 0.762)
			(stroke
				(width 0.1524)
				(type default)
			)
			(layer "B.SilkS")
		)
		(fp_line
			(start 1.524 0.762)
			(end 1.524 -0.762)
			(stroke
				(width 0.1524)
				(type default)
			)
			(layer "B.SilkS")
		)
		(fp_line
			(start -1.524 -0.762)
			(end -1.524 0.762)
			(stroke
				(width 0.1524)
				(type default)
			)
			(layer "B.SilkS")
		)
		(fp_line
			(start 1.524 -0.762)
			(end -1.524 -0.762)
			(stroke
				(width 0.1524)
				(type default)
			)
			(layer "B.SilkS")
		)
		(fp_line
			(start -1.1049 0.724916)
			(end -1.1049 -0.724916)
			(stroke
				(width 0.1)
				(type default)
			)
			(layer "B.Fab")
		)
		(fp_line
			(start 1.1049 0.724916)
			(end -1.1049 0.724916)
			(stroke
				(width 0.1)
				(type default)
			)
			(layer "B.Fab")
		)
		(fp_line
			(start -1.1049 -0.724916)
			(end 1.1049 -0.724916)
			(stroke
				(width 0.1)
				(type default)
			)
			(layer "B.Fab")
		)
		(fp_line
			(start 1.1049 -0.724916)
			(end 1.1049 0.724916)
			(stroke
				(width 0.1)
				(type default)
			)
			(layer "B.Fab")
		)
		(pad "1" smd rect
			(at 0.889 0 270)
			(size 1.016 1.27)
			(layers "B.Cu" "B.Mask" "B.Paste")
			(net "PVCCFA_EHV_FIVRA_CPU0")
		)
		(pad "2" smd rect
			(at -0.889 0 270)
			(size 1.016 1.27)
			(layers "B.Cu" "B.Mask" "B.Paste")
			(net "GND")
		)
	)
	(footprint ""
		(layer "B.Cu")
		(at 345.657932 -324.873366 -90)
		(property "Reference" "PC312_P0_1"
			(at 0 0 90)
			(layer "B.SilkS")
			(hide yes)
			(effects
				(font
					(size 1.27 1.27)
				)
				(justify mirror)
			)
		)
		(property "Value" ""
			(at 0 0 90)
			(layer "B.Fab")
			(effects
				(font
					(size 1.27 1.27)
				)
				(justify mirror)
			)
		)
		(duplicate_pad_numbers_are_jumpers no)
		(fp_line
			(start -1.524 0.762)
			(end 1.524 0.762)
			(stroke
				(width 0.1524)
				(type default)
			)
			(layer "B.SilkS")
		)
		(fp_line
			(start 1.524 0.762)
			(end 1.524 -0.762)
			(stroke
				(width 0.1524)
				(type default)
			)
			(layer "B.SilkS")
		)
		(fp_line
			(start -1.524 -0.762)
			(end -1.524 0.762)
			(stroke
				(width 0.1524)
				(type default)
			)
			(layer "B.SilkS")
		)
		(fp_line
			(start 1.524 -0.762)
			(end -1.524 -0.762)
			(stroke
				(width 0.1524)
				(type default)
			)
			(layer "B.SilkS")
		)
		(fp_line
			(start -1.1049 0.724916)
			(end -1.1049 -0.724916)
			(stroke
				(width 0.1)
				(type default)
			)
			(layer "B.Fab")
		)
		(fp_line
			(start 1.1049 0.724916)
			(end -1.1049 0.724916)
			(stroke
				(width 0.1)
				(type default)
			)
			(layer "B.Fab")
		)
		(fp_line
			(start -1.1049 -0.724916)
			(end 1.1049 -0.724916)
			(stroke
				(width 0.1)
				(type default)
			)
			(layer "B.Fab")
		)
		(fp_line
			(start 1.1049 -0.724916)
			(end 1.1049 0.724916)
			(stroke
				(width 0.1)
				(type default)
			)
			(layer "B.Fab")
		)
		(pad "1" smd rect
			(at 0.889 0 270)
			(size 1.016 1.27)
			(layers "B.Cu" "B.Mask" "B.Paste")
			(net "PVCCIN_CPU0")
		)
		(pad "2" smd rect
			(at -0.889 0 270)
			(size 1.016 1.27)
			(layers "B.Cu" "B.Mask" "B.Paste")
			(net "GND")
		)
	)
)
